# BASEBOARD_FAB2 (Tioga Pass) — schematic netlist excerpt (pin names and nets, part order shuffled) for the footprints in the layout excerpt that follows; sources: Cadence DE-HDL packaged netlist, KiCad conversion of Wiwynn_Tioga_Pass_MB.brd

CT25  CAP_A  0.1UF 16V 10% X7R  pkg 0402V  page 207 : A = VR_PVCCIN_CPU1_AIREF2 ; B = GND
C7B4  CAP  47UF 4V 20% X6S  pkg 0805  page 132 : A = PVNN_PCH_STBY ; B = GND
C8A15  CAPP  470UF 2V 20% ALUM  pkg SM  page 236 : A = P1V05_PCH_STBY ; B = GND

(kicad_pcb
	(version 20260206)
	(generator "pcbnew")
	(generator_version "10.0")
	(general
		(thickness 1.6)
		(legacy_teardrops no)
	)
	(paper "A4")
	(title_block
		(title "Wiwynn_Tioga_Pass_MB.brd")
		(comment 1 "Tioga Pass / footprints 1350-1352 of 4770")
	)
	(layers
		(0 "F.Cu" signal "TOP")
		(4 "In1.Cu" signal "L2GND")
		(6 "In2.Cu" signal "L3")
		(8 "In3.Cu" signal "L4GND")
		(10 "In4.Cu" signal "L5")
		(12 "In5.Cu" signal "L6GND")
		(14 "In6.Cu" signal "L7VCC")
		(16 "In7.Cu" signal "L8VCC")
		(18 "In8.Cu" signal "L9GND")
		(20 "In9.Cu" signal "L10")
		(22 "In10.Cu" signal "L11GND")
		(24 "In11.Cu" signal "L12")
		(26 "In12.Cu" signal "L13GND")
		(2 "B.Cu" signal "BOTTOM")
		(9 "F.Adhes" user "F.Adhesive")
		(11 "B.Adhes" user "B.Adhesive")
		(13 "F.Paste" user "Package Geometry/Pastemask Top")
		(15 "B.Paste" user "Package Geometry/Pastemask Bottom")
		(5 "F.SilkS" user "Ref Des/Silkscreen Top")
		(7 "B.SilkS" user "Ref Des/Silkscreen Bottom")
		(1 "F.Mask" user "Board Geometry/Soldermask Top")
		(3 "B.Mask" user "Board Geometry/Soldermask Bottom")
		(17 "Dwgs.User" user "User.Drawings")
		(19 "Cmts.User" user "User.Comments")
		(21 "Eco1.User" user "User.Eco1")
		(23 "Eco2.User" user "User.Eco2")
		(25 "Edge.Cuts" user "Board Geometry/Outline")
		(27 "Margin" user)
		(31 "F.CrtYd" user "Package Geometry/Place Bound Top")
		(29 "B.CrtYd" user "Package Geometry/Place Bound Bottom")
		(35 "F.Fab" user "Ref Des/Assembly Top")
		(33 "B.Fab" user "Ref Des/Assembly Bottom")
	)
	(footprint ""
		(layer "F.Cu")
		(at 29.635958 -61.716158 90)
		(property "Reference" "CT25"
			(at -0.78613 0.7874 180)
			(unlocked yes)
			(layer "F.SilkS")
			(effects
				(font
					(size 0.7874 0.5842)
					(thickness 0.1524)
				)
				(justify left)
			)
		)
		(property "Value" ""
			(at 0 0 90)
			(layer "F.Fab")
			(effects
				(font
					(size 1.27 1.27)
				)
			)
		)
		(duplicate_pad_numbers_are_jumpers no)
		(fp_poly
			(pts
				(xy 0.3048 -0.1016) (xy 0.3048 0.9906) (xy -0.3048 0.9906) (xy -0.3048 -0.1016)
			)
			(stroke
				(width 0)
				(type default)
			)
			(fill no)
			(layer "F.CrtYd")
		)
		(fp_line
			(start 0.3048 -0.1016)
			(end -0.3048 -0.1016)
			(stroke
				(width 0.1)
				(type default)
			)
			(layer "F.Fab")
		)
		(fp_line
			(start -0.3048 -0.1016)
			(end -0.3048 0.9906)
			(stroke
				(width 0.1)
				(type default)
			)
			(layer "F.Fab")
		)
		(fp_line
			(start 0.3048 0.9906)
			(end 0.3048 -0.1016)
			(stroke
				(width 0.1)
				(type default)
			)
			(layer "F.Fab")
		)
		(fp_line
			(start -0.3048 0.9906)
			(end 0.3048 0.9906)
			(stroke
				(width 0.1)
				(type default)
			)
			(layer "F.Fab")
		)
		(pad "1" smd rect
			(at 0 0 90)
			(size 0.508 0.508)
			(layers "F.Cu" "F.Mask" "F.Paste")
			(net "VR_PVCCIN_CPU1_AIREF2")
		)
		(pad "2" smd rect
			(at 0 0.889 90)
			(size 0.508 0.508)
			(layers "F.Cu" "F.Mask" "F.Paste")
			(net "GND")
		)
		(zone
			(layer "F.Cu")
			(hatch none 0.5)
			(connect_pads
				(clearance 0)
			)
			(min_thickness 0.25)
			(keepout
				(tracks allowed)
				(vias not_allowed)
				(pads allowed)
				(copperpour not_allowed)
				(footprints allowed)
			)
			(placement
				(enabled no)
				(sheetname "")
			)
			(fill
				(thermal_gap 0.5)
				(thermal_bridge_width 0.5)
				(island_removal_mode 0)
			)
			(polygon
				(pts
					(xy 29.889958 -61.462158) (xy 29.889958 -61.970158) (xy 30.270958 -61.970158) (xy 30.270958 -61.462158)
				)
			)
		)
		(zone
			(layer "F.Cu")
			(hatch none 0.5)
			(connect_pads
				(clearance 0)
			)
			(min_thickness 0.25)
			(keepout
				(tracks not_allowed)
				(vias allowed)
				(pads allowed)
				(copperpour not_allowed)
				(footprints allowed)
			)
			(placement
				(enabled no)
				(sheetname "")
			)
			(fill
				(thermal_gap 0.5)
				(thermal_bridge_width 0.5)
				(island_removal_mode 0)
			)
			(polygon
				(pts
					(xy 30.270958 -61.462158) (xy 30.270958 -61.970158) (xy 29.889958 -61.970158) (xy 29.889958 -61.462158)
				)
			)
		)
	)
	(footprint ""
		(layer "F.Cu")
		(at 381.4445 -138.9761 90)
		(property "Reference" "C7B4"
			(at 0 0 90)
			(layer "F.SilkS")
			(hide yes)
			(effects
				(font
					(size 1.27 1.27)
				)
			)
		)
		(property "Value" ""
			(at 0 0 90)
			(layer "F.Fab")
			(effects
				(font
					(size 1.27 1.27)
				)
			)
		)
		(duplicate_pad_numbers_are_jumpers no)
		(fp_rect
			(start -0.7239 -0.2159)
			(end 0.7239 1.9939)
			(stroke
				(width 0)
				(type default)
			)
			(fill no)
			(layer "F.CrtYd")
		)
		(fp_line
			(start 0.7239 -0.2159)
			(end -0.7239 -0.2159)
			(stroke
				(width 0.1)
				(type default)
			)
			(layer "F.Fab")
		)
		(fp_line
			(start -0.7239 -0.2159)
			(end -0.7239 1.9939)
			(stroke
				(width 0.1)
				(type default)
			)
			(layer "F.Fab")
		)
		(fp_line
			(start 0.7239 1.9939)
			(end 0.7239 -0.2159)
			(stroke
				(width 0.1)
				(type default)
			)
			(layer "F.Fab")
		)
		(fp_line
			(start -0.7239 1.9939)
			(end 0.7239 1.9939)
			(stroke
				(width 0.1)
				(type default)
			)
			(layer "F.Fab")
		)
		(pad "1" smd rect
			(at 0 0 90)
			(size 1.27 1.016)
			(layers "F.Cu" "F.Mask" "F.Paste")
			(net "PVNN_PCH_STBY")
		)
		(pad "2" smd rect
			(at 0 1.778 90)
			(size 1.27 1.016)
			(layers "F.Cu" "F.Mask" "F.Paste")
			(net "GND")
		)
		(zone
			(layer "F.Cu")
			(hatch none 0.5)
			(connect_pads
				(clearance 0)
			)
			(min_thickness 0.25)
			(keepout
				(tracks not_allowed)
				(vias allowed)
				(pads allowed)
				(copperpour not_allowed)
				(footprints allowed)
			)
			(placement
				(enabled no)
				(sheetname "")
			)
			(fill
				(thermal_gap 0.5)
				(thermal_bridge_width 0.5)
				(island_removal_mode 0)
			)
			(polygon
				(pts
					(xy 381.9525 -138.3411) (xy 382.7145 -138.3411) (xy 382.7145 -139.6111) (xy 381.9525 -139.6111)
				)
			)
		)
	)
	(footprint ""
		(layer "F.Cu")
		(at 391.2616 -140.2588 90)
		(property "Reference" "C8A15"
			(at 2.92862 3.24612 0)
			(unlocked yes)
			(layer "F.SilkS")
			(effects
				(font
					(size 0.4064 0.254)
					(thickness 0.1524)
				)
			)
		)
		(property "Value" ""
			(at 0 0 90)
			(layer "F.Fab")
			(effects
				(font
					(size 1.27 1.27)
				)
			)
		)
		(duplicate_pad_numbers_are_jumpers no)
		(fp_line
			(start 2.504948 -1.616456)
			(end 2.504948 1.633728)
			(stroke
				(width 0.1524)
				(type default)
			)
			(layer "F.SilkS")
		)
		(fp_line
			(start 1.6002 -1.616456)
			(end 2.504948 -1.616456)
			(stroke
				(width 0.1524)
				(type default)
			)
			(layer "F.SilkS")
		)
		(fp_line
			(start -1.6002 -1.616456)
			(end -2.563114 -1.616456)
			(stroke
				(width 0.1524)
				(type default)
			)
			(layer "F.SilkS")
		)
		(fp_line
			(start -2.563114 -1.616456)
			(end -2.563114 1.633728)
			(stroke
				(width 0.1524)
				(type default)
			)
			(layer "F.SilkS")
		)
		(fp_line
			(start 2.504948 1.633728)
			(end 1.6002 1.633728)
			(stroke
				(width 0.1524)
				(type default)
			)
			(layer "F.SilkS")
		)
		(fp_line
			(start -2.563114 1.633728)
			(end -1.6002 1.633728)
			(stroke
				(width 0.1524)
				(type default)
			)
			(layer "F.SilkS")
		)
		(fp_line
			(start 2.286 7.366)
			(end 2.286 1.63195)
			(stroke
				(width 0.1524)
				(type default)
			)
			(layer "F.SilkS")
		)
		(fp_line
			(start 2.286 7.366)
			(end 1.600708 7.366)
			(stroke
				(width 0.1524)
				(type default)
			)
			(layer "F.SilkS")
		)
		(fp_line
			(start -2.286 7.366)
			(end -2.286 1.632712)
			(stroke
				(width 0.1524)
				(type default)
			)
			(layer "F.SilkS")
		)
		(fp_line
			(start -2.286 7.366)
			(end -1.60147 7.366)
			(stroke
				(width 0.1524)
				(type default)
			)
			(layer "F.SilkS")
		)
		(fp_rect
			(start -2.286 7.366)
			(end 2.286 -0.254)
			(stroke
				(width 0)
				(type default)
			)
			(fill no)
			(layer "F.CrtYd")
		)
		(fp_line
			(start 2.286 -0.254)
			(end 2.286 7.366)
			(stroke
				(width 0.1)
				(type default)
			)
			(layer "F.Fab")
		)
		(fp_line
			(start -2.286 -0.254)
			(end 2.286 -0.254)
			(stroke
				(width 0.1)
				(type default)
			)
			(layer "F.Fab")
		)
		(fp_line
			(start 2.286 7.366)
			(end -2.286 7.366)
			(stroke
				(width 0.1)
				(type default)
			)
			(layer "F.Fab")
		)
		(fp_line
			(start -2.286 7.366)
			(end -2.286 -0.254)
			(stroke
				(width 0.1)
				(type default)
			)
			(layer "F.Fab")
		)
		(pad "1" smd rect
			(at 0 0 90)
			(size 2.54 3.048)
			(layers "F.Cu" "F.Mask" "F.Paste")
			(net "P1V05_PCH_STBY")
		)
		(pad "2" smd rect
			(at 0 7.112 90)
			(size 2.54 3.048)
			(layers "F.Cu" "F.Mask" "F.Paste")
			(net "GND")
		)
	)
)
